(kicad_pcb
	(version 20260206)
	(generator "pcbnew")
	(generator_version "10.0")
	(general
		(thickness 1.6)
		(legacy_teardrops no)
	)
	(paper "A4")
	(title_block
		(title "01162023_DA0F0TEBIF0_F0T_Expander_BD_F_brd_V02_OCP.brd")
		(comment 1 "Grand Teton / footprints 2015-2020 of 9728")
	)
	(layers
		(0 "F.Cu" signal "TOP")
		(4 "In1.Cu" signal "GND")
		(6 "In2.Cu" signal "VCC")
		(8 "In3.Cu" signal "VCC1")
		(10 "In4.Cu" signal "GND1")
		(12 "In5.Cu" signal "IN1")
		(14 "In6.Cu" signal "GND2")
		(16 "In7.Cu" signal "IN2")
		(18 "In8.Cu" signal "GND3")
		(20 "In9.Cu" signal "IN3")
		(22 "In10.Cu" signal "GND4")
		(24 "In11.Cu" signal "IN4")
		(26 "In12.Cu" signal "GND5")
		(28 "In13.Cu" signal "IN5")
		(30 "In14.Cu" signal "GND6")
		(32 "In15.Cu" signal "IN6")
		(34 "In16.Cu" signal "GND7")
		(2 "B.Cu" signal "BOTTOM")
		(9 "F.Adhes" user "F.Adhesive")
		(11 "B.Adhes" user "B.Adhesive")
		(13 "F.Paste" user "Package Geometry/Pastemask Top")
		(15 "B.Paste" user "Package Geometry/Pastemask Bottom")
		(5 "F.SilkS" user "Ref Des/Silkscreen Top")
		(7 "B.SilkS" user "Ref Des/Silkscreen Bottom")
		(1 "F.Mask" user "Board Geometry/Soldermask Top")
		(3 "B.Mask" user "Board Geometry/Soldermask Bottom")
		(17 "Dwgs.User" user "User.Drawings")
		(19 "Cmts.User" user "User.Comments")
		(21 "Eco1.User" user "User.Eco1")
		(23 "Eco2.User" user "User.Eco2")
		(25 "Edge.Cuts" user "Board Geometry/Outline")
		(27 "Margin" user)
		(31 "F.CrtYd" user "Package Geometry/Place Bound Top")
		(29 "B.CrtYd" user "Package Geometry/Place Bound Bottom")
		(35 "F.Fab" user "Ref Des/Assembly Top")
		(33 "B.Fab" user "Ref Des/Assembly Bottom")
	)
	(footprint ""
		(layer "F.Cu")
		(at 198.214234 -140.134848 -90)
		(property "Reference" "R197"
			(at 0 0 270)
			(layer "F.SilkS")
			(hide yes)
			(effects
				(font
					(size 1.27 1.27)
				)
			)
		)
		(property "Value" ""
			(at 0 0 270)
			(layer "F.Fab")
			(effects
				(font
					(size 1.27 1.27)
				)
			)
		)
		(duplicate_pad_numbers_are_jumpers no)
		(fp_line
			(start -0.7874 0.4064)
			(end -0.7874 -0.4064)
			(stroke
				(width 0.1524)
				(type default)
			)
			(layer "F.SilkS")
		)
		(fp_line
			(start 0.7874 0.4064)
			(end -0.7874 0.4064)
			(stroke
				(width 0.1524)
				(type default)
			)
			(layer "F.SilkS")
		)
		(fp_line
			(start -0.7874 -0.4064)
			(end 0.7874 -0.4064)
			(stroke
				(width 0.1524)
				(type default)
			)
			(layer "F.SilkS")
		)
		(fp_line
			(start 0.7874 -0.4064)
			(end 0.7874 0.4064)
			(stroke
				(width 0.1524)
				(type default)
			)
			(layer "F.SilkS")
		)
		(fp_line
			(start -0.67945 0.3048)
			(end -0.67945 -0.305054)
			(stroke
				(width 0.1)
				(type default)
			)
			(layer "F.Fab")
		)
		(fp_line
			(start -0.12065 0.3048)
			(end -0.67945 0.3048)
			(stroke
				(width 0.1)
				(type default)
			)
			(layer "F.Fab")
		)
		(fp_line
			(start 0.120396 0.3048)
			(end 0.120396 0.2794)
			(stroke
				(width 0.1)
				(type default)
			)
			(layer "F.Fab")
		)
		(fp_line
			(start 0.67945 0.3048)
			(end 0.120396 0.3048)
			(stroke
				(width 0.1)
				(type default)
			)
			(layer "F.Fab")
		)
		(fp_line
			(start -0.12065 0.2794)
			(end -0.12065 0.3048)
			(stroke
				(width 0.1)
				(type default)
			)
			(layer "F.Fab")
		)
		(fp_line
			(start 0.120396 0.2794)
			(end -0.12065 0.2794)
			(stroke
				(width 0.1)
				(type default)
			)
			(layer "F.Fab")
		)
		(fp_line
			(start -0.12065 -0.2794)
			(end 0.12065 -0.2794)
			(stroke
				(width 0.1)
				(type default)
			)
			(layer "F.Fab")
		)
		(fp_line
			(start 0.12065 -0.2794)
			(end 0.12065 -0.3048)
			(stroke
				(width 0.1)
				(type default)
			)
			(layer "F.Fab")
		)
		(fp_line
			(start 0.12065 -0.3048)
			(end 0.67945 -0.3048)
			(stroke
				(width 0.1)
				(type default)
			)
			(layer "F.Fab")
		)
		(fp_line
			(start 0.67945 -0.3048)
			(end 0.67945 0.3048)
			(stroke
				(width 0.1)
				(type default)
			)
			(layer "F.Fab")
		)
		(fp_line
			(start -0.67945 -0.305054)
			(end -0.12065 -0.305054)
			(stroke
				(width 0.1)
				(type default)
			)
			(layer "F.Fab")
		)
		(fp_line
			(start -0.12065 -0.305054)
			(end -0.12065 -0.2794)
			(stroke
				(width 0.1)
				(type default)
			)
			(layer "F.Fab")
		)
		(pad "1" smd circle
			(at -0.40005 0 270)
			(size 0 0)
			(layers "F.Cu" "F.Mask" "F.Paste")
			(net "P3V3_AUX")
		)
		(pad "2" smd circle
			(at 0.40005 0 270)
			(size 0 0)
			(layers "F.Cu" "F.Mask" "F.Paste")
			(net "HP_NIC3_EN")
		)
	)
	(footprint ""
		(layer "F.Cu")
		(at 149.387814 -288.419032)
		(property "Reference" "C3229"
			(at 0 0 0)
			(layer "F.SilkS")
			(hide yes)
			(effects
				(font
					(size 1.27 1.27)
				)
			)
		)
		(property "Value" ""
			(at 0 0 0)
			(layer "F.Fab")
			(effects
				(font
					(size 1.27 1.27)
				)
			)
		)
		(duplicate_pad_numbers_are_jumpers no)
		(fp_line
			(start -1.2954 -0.5842)
			(end 1.2954 -0.5842)
			(stroke
				(width 0.1524)
				(type default)
			)
			(layer "F.SilkS")
		)
		(fp_line
			(start -1.2954 0.5842)
			(end -1.2954 -0.5842)
			(stroke
				(width 0.1524)
				(type default)
			)
			(layer "F.SilkS")
		)
		(fp_line
			(start 1.2954 -0.5842)
			(end 1.2954 0.5842)
			(stroke
				(width 0.1524)
				(type default)
			)
			(layer "F.SilkS")
		)
		(fp_line
			(start 1.2954 0.5842)
			(end -1.2954 0.5842)
			(stroke
				(width 0.1524)
				(type default)
			)
			(layer "F.SilkS")
		)
		(fp_line
			(start -1.1938 -0.4064)
			(end -0.8636 -0.4064)
			(stroke
				(width 0.1)
				(type default)
			)
			(layer "F.Fab")
		)
		(fp_line
			(start -1.1938 0.4064)
			(end -1.1938 -0.4064)
			(stroke
				(width 0.1)
				(type default)
			)
			(layer "F.Fab")
		)
		(fp_line
			(start -0.8636 -0.4572)
			(end 0.8636 -0.4572)
			(stroke
				(width 0.1)
				(type default)
			)
			(layer "F.Fab")
		)
		(fp_line
			(start -0.8636 -0.4064)
			(end -0.8636 -0.4572)
			(stroke
				(width 0.1)
				(type default)
			)
			(layer "F.Fab")
		)
		(fp_line
			(start -0.8636 0.4064)
			(end -1.1938 0.4064)
			(stroke
				(width 0.1)
				(type default)
			)
			(layer "F.Fab")
		)
		(fp_line
			(start -0.8636 0.4572)
			(end -0.8636 0.4064)
			(stroke
				(width 0.1)
				(type default)
			)
			(layer "F.Fab")
		)
		(fp_line
			(start 0.8636 -0.4572)
			(end 0.8636 -0.4064)
			(stroke
				(width 0.1)
				(type default)
			)
			(layer "F.Fab")
		)
		(fp_line
			(start 0.8636 -0.4064)
			(end 1.1938 -0.4064)
			(stroke
				(width 0.1)
				(type default)
			)
			(layer "F.Fab")
		)
		(fp_line
			(start 0.8636 0.4064)
			(end 0.8636 0.4572)
			(stroke
				(width 0.1)
				(type default)
			)
			(layer "F.Fab")
		)
		(fp_line
			(start 0.8636 0.4572)
			(end -0.8636 0.4572)
			(stroke
				(width 0.1)
				(type default)
			)
			(layer "F.Fab")
		)
		(fp_line
			(start 1.1938 -0.4064)
			(end 1.1938 0.4064)
			(stroke
				(width 0.1)
				(type default)
			)
			(layer "F.Fab")
		)
		(fp_line
			(start 1.1938 0.4064)
			(end 0.8636 0.4064)
			(stroke
				(width 0.1)
				(type default)
			)
			(layer "F.Fab")
		)
		(pad "1" smd rect
			(at -0.7366 0 270)
			(size 0.7112 0.8128)
			(layers "F.Cu" "F.Mask" "F.Paste")
			(net "PCEPLL6_VDDA18_PEX1")
		)
		(pad "2" smd rect
			(at 0.7366 0 270)
			(size 0.7112 0.8128)
			(layers "F.Cu" "F.Mask" "F.Paste")
			(net "GND")
		)
	)
	(footprint ""
		(layer "F.Cu")
		(at 194.710558 -18.61439 90)
		(property "Reference" "U132"
			(at -1.29159 2.445512 90)
			(unlocked yes)
			(layer "F.SilkS")
			(effects
				(font
					(size 0.7874 0.5842)
					(thickness 0.1524)
				)
				(justify left)
			)
		)
		(property "Value" ""
			(at 0 0 90)
			(layer "F.Fab")
			(effects
				(font
					(size 1.27 1.27)
				)
			)
		)
		(duplicate_pad_numbers_are_jumpers no)
		(fp_line
			(start 1.463548 -1.549908)
			(end 1.463548 1.549908)
			(stroke
				(width 0.1524)
				(type default)
			)
			(layer "F.SilkS")
		)
		(fp_line
			(start 0.762 -1.549908)
			(end 1.463548 -1.549908)
			(stroke
				(width 0.1524)
				(type default)
			)
			(layer "F.SilkS")
		)
		(fp_line
			(start -0.787908 -1.549908)
			(end 0 -0.762)
			(stroke
				(width 0.1524)
				(type default)
			)
			(layer "F.SilkS")
		)
		(fp_line
			(start -1.463548 -1.549908)
			(end -0.787908 -1.549908)
			(stroke
				(width 0.1524)
				(type default)
			)
			(layer "F.SilkS")
		)
		(fp_line
			(start 0 -0.762)
			(end 0.762 -1.549908)
			(stroke
				(width 0.1524)
				(type default)
			)
			(layer "F.SilkS")
		)
		(fp_line
			(start 1.463548 1.549908)
			(end -1.463548 1.549908)
			(stroke
				(width 0.1524)
				(type default)
			)
			(layer "F.SilkS")
		)
		(fp_line
			(start -1.463548 1.549908)
			(end -1.463548 -1.549908)
			(stroke
				(width 0.1524)
				(type default)
			)
			(layer "F.SilkS")
		)
		(fp_poly
			(pts
				(xy -2.98069 -2.223516) (xy -2.761488 -1.566164) (xy -3.41884 -1.785366)
			)
			(stroke
				(width 0)
				(type default)
			)
			(fill yes)
			(layer "F.SilkS")
		)
		(fp_line
			(start 1.549908 -1.549908)
			(end 1.549908 1.549908)
			(stroke
				(width 0.1)
				(type default)
			)
			(layer "F.Fab")
		)
		(fp_line
			(start -1.549908 -1.549908)
			(end 1.549908 -1.549908)
			(stroke
				(width 0.1)
				(type default)
			)
			(layer "F.Fab")
		)
		(fp_line
			(start 1.549908 1.549908)
			(end -1.549908 1.549908)
			(stroke
				(width 0.1)
				(type default)
			)
			(layer "F.Fab")
		)
		(fp_line
			(start -1.549908 1.549908)
			(end -1.549908 -1.549908)
			(stroke
				(width 0.1)
				(type default)
			)
			(layer "F.Fab")
		)
		(fp_poly
			(pts
				(xy -3.4798 -1.359916) (xy -2.86004 -1.050036) (xy -3.4798 -0.740156)
			)
			(stroke
				(width 0)
				(type default)
			)
			(fill yes)
			(layer "F.Fab")
		)
		(pad "1" smd rect
			(at -2.175002 -1.050036 180)
			(size 0.6096 1.1684)
			(layers "F.Cu" "F.Mask" "F.Paste")
			(net "P3V3_SSD6")
		)
		(pad "2" smd rect
			(at -2.175002 -0.32512 180)
			(size 0.4318 1.1684)
			(layers "F.Cu" "F.Mask" "F.Paste")
			(net "SMB_ISO_SSD6_SCL")
		)
		(pad "3" smd rect
			(at -2.175002 0.32512 180)
			(size 0.4318 1.1684)
			(layers "F.Cu" "F.Mask" "F.Paste")
			(net "SMB_ISO_SSD6_SDA")
		)
		(pad "4" smd rect
			(at -2.175002 1.050036 180)
			(size 0.6096 1.1684)
			(layers "F.Cu" "F.Mask" "F.Paste")
			(net "GND")
		)
		(pad "5" smd rect
			(at 2.175002 1.050036 180)
			(size 0.6096 1.1684)
			(layers "F.Cu" "F.Mask" "F.Paste")
			(net "SMB_SSD6_ISO_EN")
		)
		(pad "6" smd rect
			(at 2.175002 0.32512 180)
			(size 0.4318 1.1684)
			(layers "F.Cu" "F.Mask" "F.Paste")
			(net "SMB_BIC_I2C9_MUX0_SSD6_R_SDA")
		)
		(pad "7" smd rect
			(at 2.175002 -0.32512 180)
			(size 0.4318 1.1684)
			(layers "F.Cu" "F.Mask" "F.Paste")
			(net "SMB_BIC_I2C9_MUX0_SSD6_R_SCL")
		)
		(pad "8" smd rect
			(at 2.175002 -1.050036 180)
			(size 0.6096 1.1684)
			(layers "F.Cu" "F.Mask" "F.Paste")
			(net "P3V3_AUX")
		)
	)
	(footprint ""
		(layer "F.Cu")
		(at 62.261242 -350.098614 90)
		(property "Reference" "C128"
			(at 0 0 90)
			(layer "F.SilkS")
			(hide yes)
			(effects
				(font
					(size 1.27 1.27)
				)
			)
		)
		(property "Value" ""
			(at 0 0 90)
			(layer "F.Fab")
			(effects
				(font
					(size 1.27 1.27)
				)
			)
		)
		(duplicate_pad_numbers_are_jumpers no)
		(fp_line
			(start 0.299974 -0.150114)
			(end 0.299974 0.150114)
			(stroke
				(width 0.1)
				(type default)
			)
			(layer "F.Fab")
		)
		(fp_line
			(start -0.299974 -0.150114)
			(end 0.299974 -0.150114)
			(stroke
				(width 0.1)
				(type default)
			)
			(layer "F.Fab")
		)
		(fp_line
			(start 0.299974 0.150114)
			(end -0.299974 0.150114)
			(stroke
				(width 0.1)
				(type default)
			)
			(layer "F.Fab")
		)
		(fp_line
			(start -0.299974 0.150114)
			(end -0.299974 -0.150114)
			(stroke
				(width 0.1)
				(type default)
			)
			(layer "F.Fab")
		)
		(pad "1" smd rect
			(at -0.2667 0 90)
			(size 0.3048 0.381)
			(layers "F.Cu" "F.Mask" "F.Paste")
			(net "P5E_PEX0_STN5_TX_DN<80>")
		)
		(pad "2" smd rect
			(at 0.2667 0 90)
			(size 0.3048 0.381)
			(layers "F.Cu" "F.Mask" "F.Paste")
			(net "P5E_PEX0_STN5_TX_C_DN<80>")
		)
	)
	(footprint ""
		(layer "F.Cu")
		(at 5.260086 -43.637708 90)
		(property "Reference" "PC670"
			(at 0 0 90)
			(layer "F.SilkS")
			(hide yes)
			(effects
				(font
					(size 1.27 1.27)
				)
			)
		)
		(property "Value" ""
			(at 0 0 90)
			(layer "F.Fab")
			(effects
				(font
					(size 1.27 1.27)
				)
			)
		)
		(duplicate_pad_numbers_are_jumpers no)
		(fp_line
			(start 0.7874 -0.4064)
			(end 0.7874 0.4064)
			(stroke
				(width 0.1524)
				(type default)
			)
			(layer "F.SilkS")
		)
		(fp_line
			(start -0.7874 -0.4064)
			(end 0.7874 -0.4064)
			(stroke
				(width 0.1524)
				(type default)
			)
			(layer "F.SilkS")
		)
		(fp_line
			(start 0.7874 0.4064)
			(end -0.7874 0.4064)
			(stroke
				(width 0.1524)
				(type default)
			)
			(layer "F.SilkS")
		)
		(fp_line
			(start -0.7874 0.4064)
			(end -0.7874 -0.4064)
			(stroke
				(width 0.1524)
				(type default)
			)
			(layer "F.SilkS")
		)
		(fp_line
			(start -0.12065 -0.305054)
			(end -0.12065 -0.2794)
			(stroke
				(width 0.1)
				(type default)
			)
			(layer "F.Fab")
		)
		(fp_line
			(start -0.67945 -0.305054)
			(end -0.12065 -0.305054)
			(stroke
				(width 0.1)
				(type default)
			)
			(layer "F.Fab")
		)
		(fp_line
			(start 0.67945 -0.3048)
			(end 0.67945 0.3048)
			(stroke
				(width 0.1)
				(type default)
			)
			(layer "F.Fab")
		)
		(fp_line
			(start 0.12065 -0.3048)
			(end 0.67945 -0.3048)
			(stroke
				(width 0.1)
				(type default)
			)
			(layer "F.Fab")
		)
		(fp_line
			(start 0.12065 -0.2794)
			(end 0.12065 -0.3048)
			(stroke
				(width 0.1)
				(type default)
			)
			(layer "F.Fab")
		)
		(fp_line
			(start -0.12065 -0.2794)
			(end 0.12065 -0.2794)
			(stroke
				(width 0.1)
				(type default)
			)
			(layer "F.Fab")
		)
		(fp_line
			(start 0.120396 0.2794)
			(end -0.12065 0.2794)
			(stroke
				(width 0.1)
				(type default)
			)
			(layer "F.Fab")
		)
		(fp_line
			(start -0.12065 0.2794)
			(end -0.12065 0.3048)
			(stroke
				(width 0.1)
				(type default)
			)
			(layer "F.Fab")
		)
		(fp_line
			(start 0.67945 0.3048)
			(end 0.120396 0.3048)
			(stroke
				(width 0.1)
				(type default)
			)
			(layer "F.Fab")
		)
		(fp_line
			(start 0.120396 0.3048)
			(end 0.120396 0.2794)
			(stroke
				(width 0.1)
				(type default)
			)
			(layer "F.Fab")
		)
		(fp_line
			(start -0.12065 0.3048)
			(end -0.67945 0.3048)
			(stroke
				(width 0.1)
				(type default)
			)
			(layer "F.Fab")
		)
		(fp_line
			(start -0.67945 0.3048)
			(end -0.67945 -0.305054)
			(stroke
				(width 0.1)
				(type default)
			)
			(layer "F.Fab")
		)
		(pad "1" smd circle
			(at -0.40005 0 90)
			(size 0 0)
			(layers "F.Cu" "F.Mask" "F.Paste")
			(net "P3V3_SSD0_CO_GATE")
		)
		(pad "2" smd circle
			(at 0.40005 0 90)
			(size 0 0)
			(layers "F.Cu" "F.Mask" "F.Paste")
			(net "GND")
		)
	)
	(footprint ""
		(layer "F.Cu")
		(at 196.639434 -138.661648 180)
		(property "Reference" "R192"
			(at 0 0 180)
			(layer "F.SilkS")
			(hide yes)
			(effects
				(font
					(size 1.27 1.27)
				)
			)
		)
		(property "Value" ""
			(at 0 0 180)
			(layer "F.Fab")
			(effects
				(font
					(size 1.27 1.27)
				)
			)
		)
		(duplicate_pad_numbers_are_jumpers no)
		(fp_line
			(start 0.7874 0.4064)
			(end -0.7874 0.4064)
			(stroke
				(width 0.1524)
				(type default)
			)
			(layer "F.SilkS")
		)
		(fp_line
			(start 0.7874 -0.4064)
			(end 0.7874 0.4064)
			(stroke
				(width 0.1524)
				(type default)
			)
			(layer "F.SilkS")
		)
		(fp_line
			(start -0.7874 0.4064)
			(end -0.7874 -0.4064)
			(stroke
				(width 0.1524)
				(type default)
			)
			(layer "F.SilkS")
		)
		(fp_line
			(start -0.7874 -0.4064)
			(end 0.7874 -0.4064)
			(stroke
				(width 0.1524)
				(type default)
			)
			(layer "F.SilkS")
		)
		(fp_line
			(start 0.67945 0.3048)
			(end 0.120396 0.3048)
			(stroke
				(width 0.1)
				(type default)
			)
			(layer "F.Fab")
		)
		(fp_line
			(start 0.67945 -0.3048)
			(end 0.67945 0.3048)
			(stroke
				(width 0.1)
				(type default)
			)
			(layer "F.Fab")
		)
		(fp_line
			(start 0.12065 -0.2794)
			(end 0.12065 -0.3048)
			(stroke
				(width 0.1)
				(type default)
			)
			(layer "F.Fab")
		)
		(fp_line
			(start 0.12065 -0.3048)
			(end 0.67945 -0.3048)
			(stroke
				(width 0.1)
				(type default)
			)
			(layer "F.Fab")
		)
		(fp_line
			(start 0.120396 0.3048)
			(end 0.120396 0.2794)
			(stroke
				(width 0.1)
				(type default)
			)
			(layer "F.Fab")
		)
		(fp_line
			(start 0.120396 0.2794)
			(end -0.12065 0.2794)
			(stroke
				(width 0.1)
				(type default)
			)
			(layer "F.Fab")
		)
		(fp_line
			(start -0.12065 0.3048)
			(end -0.67945 0.3048)
			(stroke
				(width 0.1)
				(type default)
			)
			(layer "F.Fab")
		)
		(fp_line
			(start -0.12065 0.2794)
			(end -0.12065 0.3048)
			(stroke
				(width 0.1)
				(type default)
			)
			(layer "F.Fab")
		)
		(fp_line
			(start -0.12065 -0.2794)
			(end 0.12065 -0.2794)
			(stroke
				(width 0.1)
				(type default)
			)
			(layer "F.Fab")
		)
		(fp_line
			(start -0.12065 -0.305054)
			(end -0.12065 -0.2794)
			(stroke
				(width 0.1)
				(type default)
			)
			(layer "F.Fab")
		)
		(fp_line
			(start -0.67945 0.3048)
			(end -0.67945 -0.305054)
			(stroke
				(width 0.1)
				(type default)
			)
			(layer "F.Fab")
		)
		(fp_line
			(start -0.67945 -0.305054)
			(end -0.12065 -0.305054)
			(stroke
				(width 0.1)
				(type default)
			)
			(layer "F.Fab")
		)
		(pad "1" smd circle
			(at -0.40005 0 180)
			(size 0 0)
			(layers "F.Cu" "F.Mask" "F.Paste")
			(net "PRSNT_NIC3_N")
		)
		(pad "2" smd circle
			(at 0.40005 0 180)
			(size 0 0)
			(layers "F.Cu" "F.Mask" "F.Paste")
			(net "PRSNTB0_NIC3_N")
		)
	)
)
